#ISCELL
  mstr_misc prelim *
  *
#ISCELL
  mstr_symbols design_note *
  *
#ISCELL
  mstr_symbols intel_corp_bpage *
  *
#ISCELL
  mstr_standard tap *
  page30_i1
#ISCELL
  mstr_standard tap *
  page30_i10
#ISCELL
  mstr_standard tap *
  page30_i11
#ISCELL
  mstr_standard tap *
  page30_i12
#ISCELL
  mstr_standard tap *
  page30_i13
#ISCELL
  mstr_standard tap *
  page30_i14
#ISCELL
  mstr_standard tap *
  page30_i15
#ISCELL
  mstr_standard tap *
  page30_i16
#ISCELL
  mstr_standard tap *
  page30_i17
#ISCELL
  mstr_standard tap *
  page30_i18
#ISCELL
  mstr_standard tap *
  page30_i19
#ISCELL
  mstr_standard tap *
  page30_i2
#ISCELL
  mstr_standard tap *
  page30_i20
#ISCELL
  mstr_standard tap *
  page30_i21
#ISCELL
  mstr_standard tap *
  page30_i22
#ISCELL
  mstr_standard tap *
  page30_i24
#ISCELL
  mstr_standard tap *
  page30_i25
#ISCELL
  mstr_standard tap *
  page30_i26
#ISCELL
  mstr_standard tap *
  page30_i27
#ISCELL
  mstr_standard tap *
  page30_i28
#ISCELL
  mstr_standard tap *
  page30_i29
#ISCELL
  mstr_standard tap *
  page30_i3
#ISCELL
  mstr_standard tap *
  page30_i30
#ISCELL
  mstr_standard tap *
  page30_i31
#ISCELL
  mstr_standard tap *
  page30_i32
#ISCELL
  mstr_standard tap *
  page30_i33
#ISCELL
  mstr_standard tap *
  page30_i34
#ISCELL
  mstr_standard tap *
  page30_i35
#ISCELL
  mstr_standard tap *
  page30_i36
#ISCELL
  mstr_standard tap *
  page30_i37
#ISCELL
  mstr_standard tap *
  page30_i38
#ISCELL
  mstr_standard tap *
  page30_i39
#ISCELL
  mstr_standard tap *
  page30_i40
#ISCELL
  mstr_standard tap *
  page30_i41
#ISCELL
  mstr_standard tap *
  page30_i42
#ISCELL
  mstr_standard tap *
  page30_i43
#ISCELL
  mstr_standard tap *
  page30_i44
#ISCELL
  mstr_standard tap *
  page30_i45
#ISCELL
  mstr_standard tap *
  page30_i46
#ISCELL
  mstr_standard tap *
  page30_i47
#ISCELL
  mstr_standard tap *
  page30_i48
#ISCELL
  mstr_standard tap *
  page30_i49
#ISCELL
  mstr_standard tap *
  page30_i51
#ISCELL
  mstr_standard tap *
  page30_i52
#ISCELL
  mstr_standard tap *
  page30_i53
#ISCELL
  mstr_standard tap *
  page30_i54
#ISCELL
  mstr_standard tap *
  page30_i55
#ISCELL
  mstr_standard tap *
  page30_i56
#ISCELL
  mstr_standard tap *
  page30_i57
#ISCELL
  mstr_standard tap *
  page30_i58
#ISCELL
  mstr_standard tap *
  page30_i59
#ISCELL
  mstr_standard tap *
  page30_i6
#ISCELL
  mstr_standard tap *
  page30_i60
#ISCELL
  mstr_standard tap *
  page30_i61
#ISCELL
  mstr_standard tap *
  page30_i62
#ISCELL
  mstr_standard tap *
  page30_i64
#ISCELL
  mstr_standard tap *
  page30_i65
#ISCELL
  mstr_standard tap *
  page30_i66
#ISCELL
  mstr_standard tap *
  page30_i67
#ISCELL
  mstr_standard tap *
  page30_i7
#ISCELL
  mstr_standard offpage *
  page30_i70
#ISCELL
  mstr_standard offpage *
  page30_i71
#ISCELL
  mstr_standard offpage *
  page30_i74
#ISCELL
  mstr_standard offpage *
  page30_i75
#ISCELL
  mstr_standard tap *
  page30_i78
#ISCELL
  mstr_standard tap *
  page30_i79
#ISCELL
  mstr_standard tap *
  page30_i8
#ISCELL
  mstr_standard offpage *
  page30_i80
#ISCELL
  mstr_standard offpage *
  page30_i81
#ISCELL
  mstr_standard offpage *
  page30_i82
#ISCELL
  mstr_standard offpage *
  page30_i83
#CELL
  chpset_lib skx_ext_b *
  page30_i84
#ISCELL
  mstr_standard tap *
  page30_i9
